(kicad_pcb
	(version 20260206)
	(generator "pcbnew")
	(generator_version "10.0")
	(general
		(thickness 1.6)
		(legacy_teardrops no)
	)
	(paper "A4")
	(title_block
		(title "v1-chassis-manager — T6M_CM_d_v01_1031_1645.brd")
		(comment 1 "Open CloudServer (Microsoft) / footprints 2333-2342 of 2512")
	)
	(layers
		(0 "F.Cu" signal "TOP")
		(4 "In1.Cu" signal "GND1")
		(6 "In2.Cu" signal "IN1")
		(8 "In3.Cu" signal "VCC1")
		(10 "In4.Cu" signal "VCC2")
		(12 "In5.Cu" signal "GND2")
		(14 "In6.Cu" signal "IN2")
		(16 "In7.Cu" signal "IN3")
		(18 "In8.Cu" signal "GND3")
		(2 "B.Cu" signal "BOTTOM")
		(9 "F.Adhes" user "F.Adhesive")
		(11 "B.Adhes" user "B.Adhesive")
		(13 "F.Paste" user "Package Geometry/Pastemask Top")
		(15 "B.Paste" user "Package Geometry/Pastemask Bottom")
		(5 "F.SilkS" user "Ref Des/Silkscreen Top")
		(7 "B.SilkS" user "Ref Des/Silkscreen Bottom")
		(1 "F.Mask" user "Board Geometry/Soldermask Top")
		(3 "B.Mask" user "Board Geometry/Soldermask Bottom")
		(17 "Dwgs.User" user "User.Drawings")
		(19 "Cmts.User" user "User.Comments")
		(21 "Eco1.User" user "User.Eco1")
		(23 "Eco2.User" user "User.Eco2")
		(25 "Edge.Cuts" user "Board Geometry/Outline")
		(27 "Margin" user)
		(31 "F.CrtYd" user "Package Geometry/Place Bound Top")
		(29 "B.CrtYd" user "Package Geometry/Place Bound Bottom")
		(35 "F.Fab" user "Ref Des/Assembly Top")
		(33 "B.Fab" user "Ref Des/Assembly Bottom")
	)
	(footprint ""
		(layer "B.Cu")
		(at 61.96076 -185.205624 -90)
		(property "Reference" "C676"
			(at -4.15163 0.002286 270)
			(unlocked yes)
			(layer "B.SilkS")
			(effects
				(font
					(size 0.7874 0.5842)
					(thickness 0.1524)
				)
				(justify left mirror)
			)
		)
		(property "Value" ""
			(at 0 0 90)
			(layer "B.Fab")
			(effects
				(font
					(size 1.27 1.27)
				)
				(justify mirror)
			)
		)
		(duplicate_pad_numbers_are_jumpers no)
		(fp_line
			(start -0.7874 0.4064)
			(end 0.7874 0.4064)
			(stroke
				(width 0.1524)
				(type default)
			)
			(layer "B.SilkS")
		)
		(fp_line
			(start 0.7874 0.4064)
			(end 0.7874 -0.4064)
			(stroke
				(width 0.1524)
				(type default)
			)
			(layer "B.SilkS")
		)
		(fp_line
			(start 0 0.381)
			(end 0 -0.381)
			(stroke
				(width 0.1524)
				(type default)
			)
			(layer "B.SilkS")
		)
		(fp_line
			(start -0.7874 -0.4064)
			(end -0.7874 0.4064)
			(stroke
				(width 0.1524)
				(type default)
			)
			(layer "B.SilkS")
		)
		(fp_line
			(start 0.7874 -0.4064)
			(end -0.7874 -0.4064)
			(stroke
				(width 0.1524)
				(type default)
			)
			(layer "B.SilkS")
		)
		(fp_poly
			(pts
				(xy 0.5334 0.254) (xy 0.635 0.254) (xy 0.635 0.2286) (xy 0.635 -0.254) (xy 0.5334 -0.254) (xy 0.5334 -0.2794)
				(xy -0.5334 -0.2794) (xy -0.5334 -0.254) (xy -0.635 -0.254) (xy -0.635 0.254) (xy -0.5334 0.254)
				(xy -0.5334 0.2794) (xy 0.508 0.2794) (xy 0.5334 0.2794)
			)
			(stroke
				(width 0)
				(type default)
			)
			(fill no)
			(layer "B.CrtYd")
		)
		(pad "1" smd rect
			(at -0.40005 0 90)
			(size 0.4572 0.508)
			(layers "B.Cu" "B.Mask" "B.Paste")
			(net "UART_T1_NODE2_RXD")
		)
		(pad "2" smd rect
			(at 0.40005 0 90)
			(size 0.4572 0.508)
			(layers "B.Cu" "B.Mask" "B.Paste")
			(net "GND")
		)
	)
	(footprint ""
		(layer "B.Cu")
		(at 94.451932 -173.140624 180)
		(property "Reference" "R719"
			(at -1.83642 -14.364716 0)
			(unlocked yes)
			(layer "B.SilkS")
			(effects
				(font
					(size 0.7874 0.5842)
					(thickness 0.1524)
				)
				(justify left mirror)
			)
		)
		(property "Value" ""
			(at 0 0 0)
			(layer "B.Fab")
			(effects
				(font
					(size 1.27 1.27)
				)
				(justify mirror)
			)
		)
		(duplicate_pad_numbers_are_jumpers no)
		(fp_line
			(start 0.7874 0.4064)
			(end 0.7874 -0.4064)
			(stroke
				(width 0.1524)
				(type default)
			)
			(layer "B.SilkS")
		)
		(fp_line
			(start 0.7874 -0.4064)
			(end -0.7874 -0.4064)
			(stroke
				(width 0.1524)
				(type default)
			)
			(layer "B.SilkS")
		)
		(fp_line
			(start -0.7874 0.4064)
			(end 0.7874 0.4064)
			(stroke
				(width 0.1524)
				(type default)
			)
			(layer "B.SilkS")
		)
		(fp_line
			(start -0.7874 -0.4064)
			(end -0.7874 0.4064)
			(stroke
				(width 0.1524)
				(type default)
			)
			(layer "B.SilkS")
		)
		(fp_poly
			(pts
				(xy 0.508 0.2794) (xy 0.508 0.2286) (xy 0.635 0.2286) (xy 0.635 -0.254) (xy 0.5334 -0.254) (xy 0.5334 -0.2794)
				(xy -0.5334 -0.2794) (xy -0.5334 -0.254) (xy -0.635 -0.254) (xy -0.635 0.254) (xy -0.5334 0.254)
				(xy -0.5334 0.2794)
			)
			(stroke
				(width 0)
				(type default)
			)
			(fill no)
			(layer "B.CrtYd")
		)
		(pad "1" smd rect
			(at -0.40005 0)
			(size 0.4572 0.508)
			(layers "B.Cu" "B.Mask" "B.Paste")
			(net "N21699606")
		)
		(pad "2" smd rect
			(at 0.40005 0)
			(size 0.4572 0.508)
			(layers "B.Cu" "B.Mask" "B.Paste")
			(net "GND")
		)
	)
	(footprint ""
		(layer "B.Cu")
		(at 130.514852 -151.03475 180)
		(property "Reference" "C871"
			(at -1.054862 -2.075434 0)
			(unlocked yes)
			(layer "B.SilkS")
			(effects
				(font
					(size 0.7874 0.5842)
					(thickness 0.1524)
				)
				(justify left mirror)
			)
		)
		(property "Value" ""
			(at 0 0 0)
			(layer "B.Fab")
			(effects
				(font
					(size 1.27 1.27)
				)
				(justify mirror)
			)
		)
		(duplicate_pad_numbers_are_jumpers no)
		(fp_line
			(start 0.7874 0.4064)
			(end 0.7874 -0.4064)
			(stroke
				(width 0.1524)
				(type default)
			)
			(layer "B.SilkS")
		)
		(fp_line
			(start 0.7874 -0.4064)
			(end -0.7874 -0.4064)
			(stroke
				(width 0.1524)
				(type default)
			)
			(layer "B.SilkS")
		)
		(fp_line
			(start 0 0.381)
			(end 0 -0.381)
			(stroke
				(width 0.1524)
				(type default)
			)
			(layer "B.SilkS")
		)
		(fp_line
			(start -0.7874 0.4064)
			(end 0.7874 0.4064)
			(stroke
				(width 0.1524)
				(type default)
			)
			(layer "B.SilkS")
		)
		(fp_line
			(start -0.7874 -0.4064)
			(end -0.7874 0.4064)
			(stroke
				(width 0.1524)
				(type default)
			)
			(layer "B.SilkS")
		)
		(fp_poly
			(pts
				(xy 0.5334 0.254) (xy 0.635 0.254) (xy 0.635 0.2286) (xy 0.635 -0.254) (xy 0.5334 -0.254) (xy 0.5334 -0.2794)
				(xy -0.5334 -0.2794) (xy -0.5334 -0.254) (xy -0.635 -0.254) (xy -0.635 0.254) (xy -0.5334 0.254)
				(xy -0.5334 0.2794) (xy 0.508 0.2794) (xy 0.5334 0.2794)
			)
			(stroke
				(width 0)
				(type default)
			)
			(fill no)
			(layer "B.CrtYd")
		)
		(pad "1" smd rect
			(at -0.40005 0)
			(size 0.4572 0.508)
			(layers "B.Cu" "B.Mask" "B.Paste")
			(net "P3V3_NODE1")
		)
		(pad "2" smd rect
			(at 0.40005 0)
			(size 0.4572 0.508)
			(layers "B.Cu" "B.Mask" "B.Paste")
			(net "GND")
		)
	)
	(footprint ""
		(layer "B.Cu")
		(at 75.471274 -94.131384 -90)
		(property "Reference" "R96"
			(at 3.075432 -0.409448 270)
			(unlocked yes)
			(layer "B.SilkS")
			(effects
				(font
					(size 0.7874 0.5842)
					(thickness 0.1524)
				)
				(justify left mirror)
			)
		)
		(property "Value" ""
			(at 0 0 90)
			(layer "B.Fab")
			(effects
				(font
					(size 1.27 1.27)
				)
				(justify mirror)
			)
		)
		(duplicate_pad_numbers_are_jumpers no)
		(fp_line
			(start -0.7874 0.4064)
			(end 0.7874 0.4064)
			(stroke
				(width 0.1524)
				(type default)
			)
			(layer "B.SilkS")
		)
		(fp_line
			(start 0.7874 0.4064)
			(end 0.7874 -0.4064)
			(stroke
				(width 0.1524)
				(type default)
			)
			(layer "B.SilkS")
		)
		(fp_line
			(start -0.7874 -0.4064)
			(end -0.7874 0.4064)
			(stroke
				(width 0.1524)
				(type default)
			)
			(layer "B.SilkS")
		)
		(fp_line
			(start 0.7874 -0.4064)
			(end -0.7874 -0.4064)
			(stroke
				(width 0.1524)
				(type default)
			)
			(layer "B.SilkS")
		)
		(fp_poly
			(pts
				(xy 0.508 0.2794) (xy 0.508 0.2286) (xy 0.635 0.2286) (xy 0.635 -0.254) (xy 0.5334 -0.254) (xy 0.5334 -0.2794)
				(xy -0.5334 -0.2794) (xy -0.5334 -0.254) (xy -0.635 -0.254) (xy -0.635 0.254) (xy -0.5334 0.254)
				(xy -0.5334 0.2794)
			)
			(stroke
				(width 0)
				(type default)
			)
			(fill no)
			(layer "B.CrtYd")
		)
		(pad "1" smd rect
			(at -0.40005 0 90)
			(size 0.4572 0.508)
			(layers "B.Cu" "B.Mask" "B.Paste")
			(net "GND")
		)
		(pad "2" smd rect
			(at 0.40005 0 90)
			(size 0.4572 0.508)
			(layers "B.Cu" "B.Mask" "B.Paste")
			(net "NODE1_BIOS_MB_REV_ID2")
		)
	)
	(footprint ""
		(layer "B.Cu")
		(at 64.24676 -188.126624 -90)
		(property "Reference" "C628"
			(at -4.318254 0.390906 270)
			(unlocked yes)
			(layer "B.SilkS")
			(effects
				(font
					(size 0.7874 0.5842)
					(thickness 0.1524)
				)
				(justify left mirror)
			)
		)
		(property "Value" ""
			(at 0 0 90)
			(layer "B.Fab")
			(effects
				(font
					(size 1.27 1.27)
				)
				(justify mirror)
			)
		)
		(duplicate_pad_numbers_are_jumpers no)
		(fp_line
			(start -0.7874 0.4064)
			(end 0.7874 0.4064)
			(stroke
				(width 0.1524)
				(type default)
			)
			(layer "B.SilkS")
		)
		(fp_line
			(start 0.7874 0.4064)
			(end 0.7874 -0.4064)
			(stroke
				(width 0.1524)
				(type default)
			)
			(layer "B.SilkS")
		)
		(fp_line
			(start 0 0.381)
			(end 0 -0.381)
			(stroke
				(width 0.1524)
				(type default)
			)
			(layer "B.SilkS")
		)
		(fp_line
			(start -0.7874 -0.4064)
			(end -0.7874 0.4064)
			(stroke
				(width 0.1524)
				(type default)
			)
			(layer "B.SilkS")
		)
		(fp_line
			(start 0.7874 -0.4064)
			(end -0.7874 -0.4064)
			(stroke
				(width 0.1524)
				(type default)
			)
			(layer "B.SilkS")
		)
		(fp_poly
			(pts
				(xy 0.5334 0.254) (xy 0.635 0.254) (xy 0.635 0.2286) (xy 0.635 -0.254) (xy 0.5334 -0.254) (xy 0.5334 -0.2794)
				(xy -0.5334 -0.2794) (xy -0.5334 -0.254) (xy -0.635 -0.254) (xy -0.635 0.254) (xy -0.5334 0.254)
				(xy -0.5334 0.2794) (xy 0.508 0.2794) (xy 0.5334 0.2794)
			)
			(stroke
				(width 0)
				(type default)
			)
			(fill no)
			(layer "B.CrtYd")
		)
		(pad "1" smd rect
			(at -0.40005 0 90)
			(size 0.4572 0.508)
			(layers "B.Cu" "B.Mask" "B.Paste")
			(net "T1_NODE3_EN_R")
		)
		(pad "2" smd rect
			(at 0.40005 0 90)
			(size 0.4572 0.508)
			(layers "B.Cu" "B.Mask" "B.Paste")
			(net "GND")
		)
	)
	(footprint ""
		(layer "B.Cu")
		(at 48.75022 -156.14269 180)
		(property "Reference" "C423"
			(at 11.81354 4.520184 0)
			(unlocked yes)
			(layer "B.SilkS")
			(effects
				(font
					(size 0.7874 0.5842)
					(thickness 0.1524)
				)
				(justify left mirror)
			)
		)
		(property "Value" ""
			(at 0 0 0)
			(layer "B.Fab")
			(effects
				(font
					(size 1.27 1.27)
				)
				(justify mirror)
			)
		)
		(duplicate_pad_numbers_are_jumpers no)
		(fp_line
			(start 0.7874 0.4064)
			(end 0.7874 -0.4064)
			(stroke
				(width 0.1524)
				(type default)
			)
			(layer "B.SilkS")
		)
		(fp_line
			(start 0.7874 -0.4064)
			(end -0.7874 -0.4064)
			(stroke
				(width 0.1524)
				(type default)
			)
			(layer "B.SilkS")
		)
		(fp_line
			(start 0 0.381)
			(end 0 -0.381)
			(stroke
				(width 0.1524)
				(type default)
			)
			(layer "B.SilkS")
		)
		(fp_line
			(start -0.7874 0.4064)
			(end 0.7874 0.4064)
			(stroke
				(width 0.1524)
				(type default)
			)
			(layer "B.SilkS")
		)
		(fp_line
			(start -0.7874 -0.4064)
			(end -0.7874 0.4064)
			(stroke
				(width 0.1524)
				(type default)
			)
			(layer "B.SilkS")
		)
		(fp_poly
			(pts
				(xy 0.5334 0.254) (xy 0.635 0.254) (xy 0.635 0.2286) (xy 0.635 -0.254) (xy 0.5334 -0.254) (xy 0.5334 -0.2794)
				(xy -0.5334 -0.2794) (xy -0.5334 -0.254) (xy -0.635 -0.254) (xy -0.635 0.254) (xy -0.5334 0.254)
				(xy -0.5334 0.2794) (xy 0.508 0.2794) (xy 0.5334 0.2794)
			)
			(stroke
				(width 0)
				(type default)
			)
			(fill no)
			(layer "B.CrtYd")
		)
		(pad "1" smd rect
			(at -0.40005 0)
			(size 0.4572 0.508)
			(layers "B.Cu" "B.Mask" "B.Paste")
			(net "P1V05_LAN1")
		)
		(pad "2" smd rect
			(at 0.40005 0)
			(size 0.4572 0.508)
			(layers "B.Cu" "B.Mask" "B.Paste")
			(net "GND")
		)
	)
	(footprint ""
		(layer "B.Cu")
		(at 51.67376 -185.205624 -90)
		(property "Reference" "R834"
			(at -4.15163 -0.209804 270)
			(unlocked yes)
			(layer "B.SilkS")
			(effects
				(font
					(size 0.7874 0.5842)
					(thickness 0.1524)
				)
				(justify left mirror)
			)
		)
		(property "Value" ""
			(at 0 0 90)
			(layer "B.Fab")
			(effects
				(font
					(size 1.27 1.27)
				)
				(justify mirror)
			)
		)
		(duplicate_pad_numbers_are_jumpers no)
		(fp_line
			(start -0.7874 0.4064)
			(end 0.7874 0.4064)
			(stroke
				(width 0.1524)
				(type default)
			)
			(layer "B.SilkS")
		)
		(fp_line
			(start 0.7874 0.4064)
			(end 0.7874 -0.4064)
			(stroke
				(width 0.1524)
				(type default)
			)
			(layer "B.SilkS")
		)
		(fp_line
			(start -0.7874 -0.4064)
			(end -0.7874 0.4064)
			(stroke
				(width 0.1524)
				(type default)
			)
			(layer "B.SilkS")
		)
		(fp_line
			(start 0.7874 -0.4064)
			(end -0.7874 -0.4064)
			(stroke
				(width 0.1524)
				(type default)
			)
			(layer "B.SilkS")
		)
		(fp_poly
			(pts
				(xy 0.508 0.2794) (xy 0.508 0.2286) (xy 0.635 0.2286) (xy 0.635 -0.254) (xy 0.5334 -0.254) (xy 0.5334 -0.2794)
				(xy -0.5334 -0.2794) (xy -0.5334 -0.254) (xy -0.635 -0.254) (xy -0.635 0.254) (xy -0.5334 0.254)
				(xy -0.5334 0.2794)
			)
			(stroke
				(width 0)
				(type default)
			)
			(fill no)
			(layer "B.CrtYd")
		)
		(pad "1" smd rect
			(at -0.40005 0 90)
			(size 0.4572 0.508)
			(layers "B.Cu" "B.Mask" "B.Paste")
			(net "PSU2_DC_OK_R")
		)
		(pad "2" smd rect
			(at 0.40005 0 90)
			(size 0.4572 0.508)
			(layers "B.Cu" "B.Mask" "B.Paste")
			(net "PSU2_DC_OK_R_BUF")
		)
	)
	(footprint ""
		(layer "B.Cu")
		(at 55.552086 -127.724662 180)
		(property "Reference" "C265"
			(at 41.609518 -53.453538 0)
			(unlocked yes)
			(layer "B.SilkS")
			(effects
				(font
					(size 0.7874 0.5842)
					(thickness 0.1524)
				)
				(justify left mirror)
			)
		)
		(property "Value" ""
			(at 0 0 0)
			(layer "B.Fab")
			(effects
				(font
					(size 1.27 1.27)
				)
				(justify mirror)
			)
		)
		(duplicate_pad_numbers_are_jumpers no)
		(fp_line
			(start 0.7874 0.4064)
			(end 0.7874 -0.4064)
			(stroke
				(width 0.1524)
				(type default)
			)
			(layer "B.SilkS")
		)
		(fp_line
			(start 0.7874 -0.4064)
			(end -0.7874 -0.4064)
			(stroke
				(width 0.1524)
				(type default)
			)
			(layer "B.SilkS")
		)
		(fp_line
			(start 0 0.381)
			(end 0 -0.381)
			(stroke
				(width 0.1524)
				(type default)
			)
			(layer "B.SilkS")
		)
		(fp_line
			(start -0.7874 0.4064)
			(end 0.7874 0.4064)
			(stroke
				(width 0.1524)
				(type default)
			)
			(layer "B.SilkS")
		)
		(fp_line
			(start -0.7874 -0.4064)
			(end -0.7874 0.4064)
			(stroke
				(width 0.1524)
				(type default)
			)
			(layer "B.SilkS")
		)
		(fp_poly
			(pts
				(xy 0.5334 0.254) (xy 0.635 0.254) (xy 0.635 0.2286) (xy 0.635 -0.254) (xy 0.5334 -0.254) (xy 0.5334 -0.2794)
				(xy -0.5334 -0.2794) (xy -0.5334 -0.254) (xy -0.635 -0.254) (xy -0.635 0.254) (xy -0.5334 0.254)
				(xy -0.5334 0.2794) (xy 0.508 0.2794) (xy 0.5334 0.2794)
			)
			(stroke
				(width 0)
				(type default)
			)
			(fill no)
			(layer "B.CrtYd")
		)
		(pad "1" smd rect
			(at -0.40005 0)
			(size 0.4572 0.508)
			(layers "B.Cu" "B.Mask" "B.Paste")
			(net "BMC_NODE1_MPLLAV33")
		)
		(pad "2" smd rect
			(at 0.40005 0)
			(size 0.4572 0.508)
			(layers "B.Cu" "B.Mask" "B.Paste")
			(net "GND")
		)
	)
	(footprint ""
		(layer "B.Cu")
		(at 39.687754 -76.22794 -90)
		(property "Reference" "C36"
			(at 0.150114 1.236218 270)
			(unlocked yes)
			(layer "B.SilkS")
			(effects
				(font
					(size 0.7874 0.5842)
					(thickness 0.1524)
				)
				(justify mirror)
			)
		)
		(property "Value" ""
			(at 0 0 90)
			(layer "B.Fab")
			(effects
				(font
					(size 1.27 1.27)
				)
				(justify mirror)
			)
		)
		(duplicate_pad_numbers_are_jumpers no)
		(fp_line
			(start -1.2954 0.5842)
			(end 1.2954 0.5842)
			(stroke
				(width 0.1524)
				(type default)
			)
			(layer "B.SilkS")
		)
		(fp_line
			(start 1.2954 0.5842)
			(end 1.2954 -0.5842)
			(stroke
				(width 0.1524)
				(type default)
			)
			(layer "B.SilkS")
		)
		(fp_line
			(start -1.2954 -0.5842)
			(end -1.2954 0.5842)
			(stroke
				(width 0.1524)
				(type default)
			)
			(layer "B.SilkS")
		)
		(fp_line
			(start 0 -0.5842)
			(end 0 0.5842)
			(stroke
				(width 0.1524)
				(type default)
			)
			(layer "B.SilkS")
		)
		(fp_line
			(start 1.2954 -0.5842)
			(end -1.2954 -0.5842)
			(stroke
				(width 0.1524)
				(type default)
			)
			(layer "B.SilkS")
		)
		(fp_poly
			(pts
				(xy -0.8636 -0.4572) (xy -0.8636 -0.3556) (xy -1.143 -0.3556) (xy -1.143 0.3556) (xy -0.8636 0.3556)
				(xy -0.8636 0.4572) (xy 0.8636 0.4572) (xy 0.8636 0.3556) (xy 1.143 0.3556) (xy 1.143 -0.3556) (xy 0.8636 -0.3556)
				(xy 0.8636 -0.4572)
			)
			(stroke
				(width 0)
				(type default)
			)
			(fill no)
			(layer "B.CrtYd")
		)
		(fp_line
			(start -0.884936 0.504952)
			(end 0.884936 0.504952)
			(stroke
				(width 0.1)
				(type default)
			)
			(layer "B.Fab")
		)
		(fp_line
			(start 0.884936 0.504952)
			(end 0.884936 -0.504952)
			(stroke
				(width 0.1)
				(type default)
			)
			(layer "B.Fab")
		)
		(fp_line
			(start -0.884936 -0.504952)
			(end -0.884936 0.504952)
			(stroke
				(width 0.1)
				(type default)
			)
			(layer "B.Fab")
		)
		(fp_line
			(start 0.884936 -0.504952)
			(end -0.884936 -0.504952)
			(stroke
				(width 0.1)
				(type default)
			)
			(layer "B.Fab")
		)
		(pad "1" smd rect
			(at -0.7366 0)
			(size 0.7112 0.8128)
			(layers "B.Cu" "B.Mask" "B.Paste")
			(net "P1V05_NODE1")
		)
		(pad "2" smd rect
			(at 0.7366 0)
			(size 0.7112 0.8128)
			(layers "B.Cu" "B.Mask" "B.Paste")
			(net "GND")
		)
	)
	(footprint ""
		(layer "B.Cu")
		(at 132.978652 -151.31415 90)
		(property "Reference" "C331"
			(at 1.439926 0.660146 270)
			(unlocked yes)
			(layer "B.SilkS")
			(effects
				(font
					(size 0.7874 0.5842)
					(thickness 0.1524)
				)
				(justify left mirror)
			)
		)
		(property "Value" ""
			(at 0 0 90)
			(layer "B.Fab")
			(effects
				(font
					(size 1.27 1.27)
				)
				(justify mirror)
			)
		)
		(duplicate_pad_numbers_are_jumpers no)
		(fp_line
			(start 0.7874 -0.4064)
			(end -0.7874 -0.4064)
			(stroke
				(width 0.1524)
				(type default)
			)
			(layer "B.SilkS")
		)
		(fp_line
			(start -0.7874 -0.4064)
			(end -0.7874 0.4064)
			(stroke
				(width 0.1524)
				(type default)
			)
			(layer "B.SilkS")
		)
		(fp_line
			(start 0 0.381)
			(end 0 -0.381)
			(stroke
				(width 0.1524)
				(type default)
			)
			(layer "B.SilkS")
		)
		(fp_line
			(start 0.7874 0.4064)
			(end 0.7874 -0.4064)
			(stroke
				(width 0.1524)
				(type default)
			)
			(layer "B.SilkS")
		)
		(fp_line
			(start -0.7874 0.4064)
			(end 0.7874 0.4064)
			(stroke
				(width 0.1524)
				(type default)
			)
			(layer "B.SilkS")
		)
		(fp_poly
			(pts
				(xy 0.5334 0.254) (xy 0.635 0.254) (xy 0.635 0.2286) (xy 0.635 -0.254) (xy 0.5334 -0.254) (xy 0.5334 -0.2794)
				(xy -0.5334 -0.2794) (xy -0.5334 -0.254) (xy -0.635 -0.254) (xy -0.635 0.254) (xy -0.5334 0.254)
				(xy -0.5334 0.2794) (xy 0.508 0.2794) (xy 0.5334 0.2794)
			)
			(stroke
				(width 0)
				(type default)
			)
			(fill no)
			(layer "B.CrtYd")
		)
		(pad "1" smd rect
			(at -0.40005 0 270)
			(size 0.4572 0.508)
			(layers "B.Cu" "B.Mask" "B.Paste")
			(net "P1V0_NODE1")
		)
		(pad "2" smd rect
			(at 0.40005 0 270)
			(size 0.4572 0.508)
			(layers "B.Cu" "B.Mask" "B.Paste")
			(net "GND")
		)
	)
)
